# S9S_MB_2U (Grand Teton) — schematic netlist excerpt (pin names and nets, part order shuffled) for the footprints in the layout excerpt that follows; sources: Cadence DE-HDL packaged netlist, KiCad conversion of 03242023_DA0F0TMBIJ0_F0T_Motherboard_J_brd_V01_OCP.brd

R4585  Q_RES  1K 1% CHIP  pkg 0402LF  page 195 : A = FM_BOARD_BMC_SKU_ID0 ; B = GND
R625  Q_RES  1K 1% EMPTY  pkg 0402LF  page 127 : A = P3V3_AUX ; B = PD_PIROM_CPU1_ADDR2

(kicad_pcb
	(version 20260206)
	(generator "pcbnew")
	(generator_version "10.0")
	(general
		(thickness 1.6)
		(legacy_teardrops no)
	)
	(paper "A4")
	(title_block
		(title "03242023_DA0F0TMBIJ0_F0T_Motherboard_J_brd_V01_OCP.brd")
		(comment 1 "Grand Teton / footprints 2677-2678 of 6105")
	)
	(layers
		(0 "F.Cu" signal "TOP")
		(4 "In1.Cu" signal "GND")
		(6 "In2.Cu" signal "IN1")
		(8 "In3.Cu" signal "GND1")
		(10 "In4.Cu" signal "IN2")
		(12 "In5.Cu" signal "GND2")
		(14 "In6.Cu" signal "IN3")
		(16 "In7.Cu" signal "GND3")
		(18 "In8.Cu" signal "VCC")
		(20 "In9.Cu" signal "VCC1")
		(22 "In10.Cu" signal "GND4")
		(24 "In11.Cu" signal "IN4")
		(26 "In12.Cu" signal "GND5")
		(28 "In13.Cu" signal "IN5")
		(30 "In14.Cu" signal "GND6")
		(32 "In15.Cu" signal "IN6")
		(34 "In16.Cu" signal "GND7")
		(2 "B.Cu" signal "BOTTOM")
		(9 "F.Adhes" user "F.Adhesive")
		(11 "B.Adhes" user "B.Adhesive")
		(13 "F.Paste" user "Package Geometry/Pastemask Top")
		(15 "B.Paste" user "Package Geometry/Pastemask Bottom")
		(5 "F.SilkS" user "Ref Des/Silkscreen Top")
		(7 "B.SilkS" user "Ref Des/Silkscreen Bottom")
		(1 "F.Mask" user "Board Geometry/Soldermask Top")
		(3 "B.Mask" user "Board Geometry/Soldermask Bottom")
		(17 "Dwgs.User" user "User.Drawings")
		(19 "Cmts.User" user "User.Comments")
		(21 "Eco1.User" user "User.Eco1")
		(23 "Eco2.User" user "User.Eco2")
		(25 "Edge.Cuts" user "Board Geometry/Outline")
		(27 "Margin" user)
		(31 "F.CrtYd" user "Package Geometry/Place Bound Top")
		(29 "B.CrtYd" user "Package Geometry/Place Bound Bottom")
		(35 "F.Fab" user "Ref Des/Assembly Top")
		(33 "B.Fab" user "Ref Des/Assembly Bottom")
	)
	(footprint ""
		(layer "F.Cu")
		(at 177.9524 -94.338648 90)
		(property "Reference" "R4585"
			(at 0 0 90)
			(layer "F.SilkS")
			(hide yes)
			(effects
				(font
					(size 1.27 1.27)
				)
			)
		)
		(property "Value" ""
			(at 0 0 90)
			(layer "F.Fab")
			(effects
				(font
					(size 1.27 1.27)
				)
			)
		)
		(duplicate_pad_numbers_are_jumpers no)
		(fp_line
			(start 0.7874 -0.4064)
			(end 0.7874 0.4064)
			(stroke
				(width 0.1524)
				(type default)
			)
			(layer "F.SilkS")
		)
		(fp_line
			(start -0.7874 -0.4064)
			(end 0.7874 -0.4064)
			(stroke
				(width 0.1524)
				(type default)
			)
			(layer "F.SilkS")
		)
		(fp_line
			(start 0.7874 0.4064)
			(end -0.7874 0.4064)
			(stroke
				(width 0.1524)
				(type default)
			)
			(layer "F.SilkS")
		)
		(fp_line
			(start -0.7874 0.4064)
			(end -0.7874 -0.4064)
			(stroke
				(width 0.1524)
				(type default)
			)
			(layer "F.SilkS")
		)
		(fp_line
			(start -0.12065 -0.305054)
			(end -0.12065 -0.2794)
			(stroke
				(width 0.1)
				(type default)
			)
			(layer "F.Fab")
		)
		(fp_line
			(start -0.67945 -0.305054)
			(end -0.12065 -0.305054)
			(stroke
				(width 0.1)
				(type default)
			)
			(layer "F.Fab")
		)
		(fp_line
			(start 0.67945 -0.3048)
			(end 0.67945 0.3048)
			(stroke
				(width 0.1)
				(type default)
			)
			(layer "F.Fab")
		)
		(fp_line
			(start 0.12065 -0.3048)
			(end 0.67945 -0.3048)
			(stroke
				(width 0.1)
				(type default)
			)
			(layer "F.Fab")
		)
		(fp_line
			(start 0.12065 -0.2794)
			(end 0.12065 -0.3048)
			(stroke
				(width 0.1)
				(type default)
			)
			(layer "F.Fab")
		)
		(fp_line
			(start -0.12065 -0.2794)
			(end 0.12065 -0.2794)
			(stroke
				(width 0.1)
				(type default)
			)
			(layer "F.Fab")
		)
		(fp_line
			(start 0.120396 0.2794)
			(end -0.12065 0.2794)
			(stroke
				(width 0.1)
				(type default)
			)
			(layer "F.Fab")
		)
		(fp_line
			(start -0.12065 0.2794)
			(end -0.12065 0.3048)
			(stroke
				(width 0.1)
				(type default)
			)
			(layer "F.Fab")
		)
		(fp_line
			(start 0.67945 0.3048)
			(end 0.120396 0.3048)
			(stroke
				(width 0.1)
				(type default)
			)
			(layer "F.Fab")
		)
		(fp_line
			(start 0.120396 0.3048)
			(end 0.120396 0.2794)
			(stroke
				(width 0.1)
				(type default)
			)
			(layer "F.Fab")
		)
		(fp_line
			(start -0.12065 0.3048)
			(end -0.67945 0.3048)
			(stroke
				(width 0.1)
				(type default)
			)
			(layer "F.Fab")
		)
		(fp_line
			(start -0.67945 0.3048)
			(end -0.67945 -0.305054)
			(stroke
				(width 0.1)
				(type default)
			)
			(layer "F.Fab")
		)
		(pad "1" smd rect
			(at -0.40005 0 270)
			(size 0.4572 0.508)
			(layers "F.Cu" "F.Mask" "F.Paste")
			(net "FM_BOARD_BMC_SKU_ID0")
		)
		(pad "2" smd rect
			(at 0.40005 0 270)
			(size 0.4572 0.508)
			(layers "F.Cu" "F.Mask" "F.Paste")
			(net "GND")
		)
	)
	(footprint ""
		(layer "F.Cu")
		(at 193.93408 -351.551748 180)
		(property "Reference" "R625"
			(at 0 0 180)
			(layer "F.SilkS")
			(hide yes)
			(effects
				(font
					(size 1.27 1.27)
				)
			)
		)
		(property "Value" ""
			(at 0 0 180)
			(layer "F.Fab")
			(effects
				(font
					(size 1.27 1.27)
				)
			)
		)
		(duplicate_pad_numbers_are_jumpers no)
		(fp_line
			(start 0.7874 0.4064)
			(end -0.7874 0.4064)
			(stroke
				(width 0.1524)
				(type default)
			)
			(layer "F.SilkS")
		)
		(fp_line
			(start 0.7874 -0.4064)
			(end 0.7874 0.4064)
			(stroke
				(width 0.1524)
				(type default)
			)
			(layer "F.SilkS")
		)
		(fp_line
			(start -0.7874 0.4064)
			(end -0.7874 -0.4064)
			(stroke
				(width 0.1524)
				(type default)
			)
			(layer "F.SilkS")
		)
		(fp_line
			(start -0.7874 -0.4064)
			(end 0.7874 -0.4064)
			(stroke
				(width 0.1524)
				(type default)
			)
			(layer "F.SilkS")
		)
		(fp_line
			(start 0.67945 0.3048)
			(end 0.120396 0.3048)
			(stroke
				(width 0.1)
				(type default)
			)
			(layer "F.Fab")
		)
		(fp_line
			(start 0.67945 -0.3048)
			(end 0.67945 0.3048)
			(stroke
				(width 0.1)
				(type default)
			)
			(layer "F.Fab")
		)
		(fp_line
			(start 0.12065 -0.2794)
			(end 0.12065 -0.3048)
			(stroke
				(width 0.1)
				(type default)
			)
			(layer "F.Fab")
		)
		(fp_line
			(start 0.12065 -0.3048)
			(end 0.67945 -0.3048)
			(stroke
				(width 0.1)
				(type default)
			)
			(layer "F.Fab")
		)
		(fp_line
			(start 0.120396 0.3048)
			(end 0.120396 0.2794)
			(stroke
				(width 0.1)
				(type default)
			)
			(layer "F.Fab")
		)
		(fp_line
			(start 0.120396 0.2794)
			(end -0.12065 0.2794)
			(stroke
				(width 0.1)
				(type default)
			)
			(layer "F.Fab")
		)
		(fp_line
			(start -0.12065 0.3048)
			(end -0.67945 0.3048)
			(stroke
				(width 0.1)
				(type default)
			)
			(layer "F.Fab")
		)
		(fp_line
			(start -0.12065 0.2794)
			(end -0.12065 0.3048)
			(stroke
				(width 0.1)
				(type default)
			)
			(layer "F.Fab")
		)
		(fp_line
			(start -0.12065 -0.2794)
			(end 0.12065 -0.2794)
			(stroke
				(width 0.1)
				(type default)
			)
			(layer "F.Fab")
		)
		(fp_line
			(start -0.12065 -0.305054)
			(end -0.12065 -0.2794)
			(stroke
				(width 0.1)
				(type default)
			)
			(layer "F.Fab")
		)
		(fp_line
			(start -0.67945 0.3048)
			(end -0.67945 -0.305054)
			(stroke
				(width 0.1)
				(type default)
			)
			(layer "F.Fab")
		)
		(fp_line
			(start -0.67945 -0.305054)
			(end -0.12065 -0.305054)
			(stroke
				(width 0.1)
				(type default)
			)
			(layer "F.Fab")
		)
		(pad "1" smd circle
			(at -0.40005 0 180)
			(size 0 0)
			(layers "F.Cu" "F.Mask" "F.Paste")
			(net "P3V3_AUX")
		)
		(pad "2" smd circle
			(at 0.40005 0 180)
			(size 0 0)
			(layers "F.Cu" "F.Mask" "F.Paste")
			(net "PD_PIROM_CPU1_ADDR2")
		)
	)
)
